FILE_TYPE = MACRO_DRAWING;
SET COLOR_WIRE YELLOW;
SET COLOR_PROP ORANGE;
SET COLOR_DOT WHITE;
SET COLOR_ARC YELLOW;
SET COLOR_BODY GREEN;
SET COLOR_NOTE PURPLE;
SET PROP_DISPLAY VALUE;
SET PAGE_NUMBER P153;
FORCEADD QUANTA_TITLE_BLOCK_C..1
(0 0);
FORCEPROP 1 LAST CUSTOM_TXT_CDS <NAME_2>
J 0
(-3175 50);
FORCEPROP 1 LAST CUSTOM_TXT_CDS <NAME_1>
J 0
(-3175 175);
FORCEPROP 1 LAST CUSTOM_TXT_CDS <Q_NUMBER>
J 0
(-1403 103);
DISPLAY 1.212766 (-1403 103);
FORCEPROP 1 LAST CUSTOM_TXT_CDS <Q_PROJ>
J 0
(-2382 102);
DISPLAY 1.212766 (-2382 102);
FORCEPROP 1 LAST CUSTOM_TXT_CDS <Q_REV>
J 0
(-184 103);
DISPLAY 1.212766 (-184 103);
FORCEPROP 1 LAST CUSTOM_TXT_CDS <CON_LAST_MODIFIED>
J 0
(-1885 15);
DISPLAY 0.978723 (-1885 15);
FORCEPROP 1 LAST CUSTOM_TXT_CDS <CON_PAGE_NUM> OF <CON_TOTAL_PAGES>
J 0
(-446 18);
DISPLAY 0.978723 (-446 18);
FORCEPROP 1 LAST Q_TITLE FAN - SINGLE ROTOR
J 0
(-9250 75);
DISPLAY 2.446809 (-9250 75);
PAINT GREEN (-9250 75);
FORCEPROP 1 LAST Q_DEPT BU9
J 1
(-3763 49);
DISPLAY 1.957447 (-3763 49);
PAINT GREEN (-3763 49);
FORCEPROP 2 LAST PAGE_BORDER TRUE
J 0
(-7890 5250);
DISPLAY 0.638298 (-7890 5250);
PAINT PINK (-7890 5250);
DISPLAY INVISIBLE (-7890 5250);
FORCEPROP 1 LAST COMMENT_BODY TRUE
J 0
(12 -13);
DISPLAY 0.978723 (12 -13);
PAINT GREEN (12 -13);
DISPLAY INVISIBLE (12 -13);
FORCEPROP 2 LAST CDS_LIB pure_quanta
J 0
(0 0);
DISPLAY INVISIBLE (0 0);
FORCEPROP 1 LAST CDS_LMAN_SYM_OUTLINE -9475,6775,100,-125
J 0
(0 0);
DISPLAY 0.468085 (0 0);
PAINT GREEN (0 0);
DISPLAY INVISIBLE (0 0);
FORCEPROP 2 LAST CDS_XR_PAGE_TITLE CR-153 : @T6G_MB_LIB.T6G(SCH_1):PAGE153
J 0
(-7890 5250);
DISPLAY 0.638298 (-7890 5250);
PAINT PINK (-7890 5250);
DISPLAY INVISIBLE (-7890 5250);
FORCEPROP 2 LAST CUSTOM_TXT_CDS <XR_PAGE_TITLE>
J 0
(-7890 5250);
DISPLAY 0.638298 (-7890 5250);
PAINT PINK (-7890 5250);
DISPLAY INVISIBLE (-7890 5250);
FORCEPROP 0 LAST CDS_CON_LAST_MODIFIED Wed Mar 09 20:27:26 2022
J 0
(-1885 15);
DISPLAY INVISIBLE (-1885 15);
QUIT
